# T6G (Grand Teton) — schematic netlist excerpt (pin names and nets, part order shuffled) for the footprints in the layout excerpt that follows; sources: Cadence DE-HDL packaged netlist, KiCad conversion of 04192023_DAF0TMB3IC0_F0TG_MB_C_brd_V02_OCP.brd

C963  Q_CAP_DIFFBUS  DIFF BUS_0.22UF 6.3V 20% X6S  pkg C0201  page 63 : \1\ = P5E_CPU0_P1_TX_C_DP<1> ; \2\ = P5E_CPU0_P1_TX_DP<1>
C559  Q_CAP  100UF 4V 20% X6S  pkg C0805  page 279 : A = P0V9_CPU0_RT_2D ; B = GND
PR6561  Q_RES  8.87K 1% EMPTY  pkg 0402LF  page 363 : A = P0V9_RETIMER_CPU0_LSET2 ; B = GND
R1080  Q_RES  4.7K 5% CHIP  pkg 0201LF  page 298 : A = P1V8_CPU0_RT_1D ; B = MODE_RT_CPU0_P2

(kicad_pcb
	(version 20260206)
	(generator "pcbnew")
	(generator_version "10.0")
	(general
		(thickness 1.6)
		(legacy_teardrops no)
	)
	(paper "A4")
	(title_block
		(title "04192023_DAF0TMB3IC0_F0TG_MB_C_brd_V02_OCP.brd")
		(comment 1 "Grand Teton / footprints 2945-2948 of 8354")
	)
	(layers
		(0 "F.Cu" signal "TOP")
		(4 "In1.Cu" signal "GND")
		(6 "In2.Cu" signal "IN1")
		(8 "In3.Cu" signal "GND1")
		(10 "In4.Cu" signal "IN2")
		(12 "In5.Cu" signal "GND2")
		(14 "In6.Cu" signal "IN3")
		(16 "In7.Cu" signal "GND3")
		(18 "In8.Cu" signal "VCC")
		(20 "In9.Cu" signal "VCC1")
		(22 "In10.Cu" signal "GND4")
		(24 "In11.Cu" signal "IN4")
		(26 "In12.Cu" signal "GND5")
		(28 "In13.Cu" signal "IN5")
		(30 "In14.Cu" signal "GND6")
		(32 "In15.Cu" signal "IN6")
		(34 "In16.Cu" signal "GND7")
		(2 "B.Cu" signal "BOTTOM")
		(9 "F.Adhes" user "F.Adhesive")
		(11 "B.Adhes" user "B.Adhesive")
		(13 "F.Paste" user "Package Geometry/Pastemask Top")
		(15 "B.Paste" user "Package Geometry/Pastemask Bottom")
		(5 "F.SilkS" user "Ref Des/Silkscreen Top")
		(7 "B.SilkS" user "Ref Des/Silkscreen Bottom")
		(1 "F.Mask" user "Board Geometry/Soldermask Top")
		(3 "B.Mask" user "Board Geometry/Soldermask Bottom")
		(17 "Dwgs.User" user "User.Drawings")
		(19 "Cmts.User" user "User.Comments")
		(21 "Eco1.User" user "User.Eco1")
		(23 "Eco2.User" user "User.Eco2")
		(25 "Edge.Cuts" user "Board Geometry/Outline")
		(27 "Margin" user)
		(31 "F.CrtYd" user "Package Geometry/Place Bound Top")
		(29 "B.CrtYd" user "Package Geometry/Place Bound Bottom")
		(35 "F.Fab" user "Ref Des/Assembly Top")
		(33 "B.Fab" user "Ref Des/Assembly Bottom")
	)
	(footprint ""
		(layer "F.Cu")
		(at 304.523394 -408.801316 -90)
		(property "Reference" "C559"
			(at 0 0 270)
			(layer "F.SilkS")
			(hide yes)
			(effects
				(font
					(size 1.27 1.27)
				)
			)
		)
		(property "Value" ""
			(at 0 0 270)
			(layer "F.Fab")
			(effects
				(font
					(size 1.27 1.27)
				)
			)
		)
		(duplicate_pad_numbers_are_jumpers no)
		(fp_line
			(start -1.524 0.762)
			(end -1.524 -0.762)
			(stroke
				(width 0.1524)
				(type default)
			)
			(layer "F.SilkS")
		)
		(fp_line
			(start 1.524 0.762)
			(end -1.524 0.762)
			(stroke
				(width 0.1524)
				(type default)
			)
			(layer "F.SilkS")
		)
		(fp_line
			(start -1.524 -0.762)
			(end 1.524 -0.762)
			(stroke
				(width 0.1524)
				(type default)
			)
			(layer "F.SilkS")
		)
		(fp_line
			(start 1.524 -0.762)
			(end 1.524 0.762)
			(stroke
				(width 0.1524)
				(type default)
			)
			(layer "F.SilkS")
		)
		(fp_line
			(start -1.1049 0.724916)
			(end 1.1049 0.724916)
			(stroke
				(width 0.1)
				(type default)
			)
			(layer "F.Fab")
		)
		(fp_line
			(start 1.1049 0.724916)
			(end 1.1049 -0.724916)
			(stroke
				(width 0.1)
				(type default)
			)
			(layer "F.Fab")
		)
		(fp_line
			(start -1.1049 -0.724916)
			(end -1.1049 0.724916)
			(stroke
				(width 0.1)
				(type default)
			)
			(layer "F.Fab")
		)
		(fp_line
			(start 1.1049 -0.724916)
			(end -1.1049 -0.724916)
			(stroke
				(width 0.1)
				(type default)
			)
			(layer "F.Fab")
		)
		(pad "1" smd rect
			(at -0.889 0 90)
			(size 1.016 1.27)
			(layers "F.Cu" "F.Mask" "F.Paste")
			(net "P0V9_CPU0_RT_2D")
		)
		(pad "2" smd rect
			(at 0.889 0 90)
			(size 1.016 1.27)
			(layers "F.Cu" "F.Mask" "F.Paste")
			(net "GND")
		)
	)
	(footprint ""
		(layer "F.Cu")
		(at 331.494892 -384.32486 180)
		(property "Reference" "C963"
			(at 0 0 180)
			(layer "F.SilkS")
			(hide yes)
			(effects
				(font
					(size 1.27 1.27)
				)
			)
		)
		(property "Value" ""
			(at 0 0 180)
			(layer "F.Fab")
			(effects
				(font
					(size 1.27 1.27)
				)
			)
		)
		(duplicate_pad_numbers_are_jumpers no)
		(fp_line
			(start 0.299974 0.150114)
			(end -0.299974 0.150114)
			(stroke
				(width 0.1)
				(type default)
			)
			(layer "F.Fab")
		)
		(fp_line
			(start 0.299974 -0.150114)
			(end 0.299974 0.150114)
			(stroke
				(width 0.1)
				(type default)
			)
			(layer "F.Fab")
		)
		(fp_line
			(start -0.299974 0.150114)
			(end -0.299974 -0.150114)
			(stroke
				(width 0.1)
				(type default)
			)
			(layer "F.Fab")
		)
		(fp_line
			(start -0.299974 -0.150114)
			(end 0.299974 -0.150114)
			(stroke
				(width 0.1)
				(type default)
			)
			(layer "F.Fab")
		)
		(pad "1" smd rect
			(at -0.2667 0 180)
			(size 0.3048 0.381)
			(layers "F.Cu" "F.Mask" "F.Paste")
			(net "P5E_CPU0_P1_TX_C_DP<1>")
		)
		(pad "2" smd rect
			(at 0.2667 0 180)
			(size 0.3048 0.381)
			(layers "F.Cu" "F.Mask" "F.Paste")
			(net "P5E_CPU0_P1_TX_DP<1>")
		)
	)
	(footprint ""
		(layer "F.Cu")
		(at 401.128484 -403.818852 -90)
		(property "Reference" "R1080"
			(at 0 0 270)
			(layer "F.SilkS")
			(hide yes)
			(effects
				(font
					(size 1.27 1.27)
				)
			)
		)
		(property "Value" ""
			(at 0 0 270)
			(layer "F.Fab")
			(effects
				(font
					(size 1.27 1.27)
				)
			)
		)
		(duplicate_pad_numbers_are_jumpers no)
		(fp_line
			(start -0.32512 0.175006)
			(end -0.32512 -0.175006)
			(stroke
				(width 0.1)
				(type default)
			)
			(layer "F.Fab")
		)
		(fp_line
			(start 0.32512 0.175006)
			(end -0.32512 0.175006)
			(stroke
				(width 0.1)
				(type default)
			)
			(layer "F.Fab")
		)
		(fp_line
			(start -0.32512 -0.175006)
			(end 0.32512 -0.175006)
			(stroke
				(width 0.1)
				(type default)
			)
			(layer "F.Fab")
		)
		(fp_line
			(start 0.32512 -0.175006)
			(end 0.32512 0.175006)
			(stroke
				(width 0.1)
				(type default)
			)
			(layer "F.Fab")
		)
		(pad "1" smd rect
			(at -0.2667 0 270)
			(size 0.3048 0.381)
			(layers "F.Cu" "F.Mask" "F.Paste")
			(net "P1V8_CPU0_RT_1D")
		)
		(pad "2" smd rect
			(at 0.2667 0 90)
			(size 0.3048 0.381)
			(layers "F.Cu" "F.Mask" "F.Paste")
			(net "MODE_RT_CPU0_P2")
		)
	)
	(footprint ""
		(layer "F.Cu")
		(at 453.210676 -402.801328)
		(property "Reference" "PR6561"
			(at 0 0 0)
			(layer "F.SilkS")
			(hide yes)
			(effects
				(font
					(size 1.27 1.27)
				)
			)
		)
		(property "Value" ""
			(at 0 0 0)
			(layer "F.Fab")
			(effects
				(font
					(size 1.27 1.27)
				)
			)
		)
		(duplicate_pad_numbers_are_jumpers no)
		(fp_line
			(start -0.7874 -0.4064)
			(end 0.7874 -0.4064)
			(stroke
				(width 0.1524)
				(type default)
			)
			(layer "F.SilkS")
		)
		(fp_line
			(start -0.7874 0.4064)
			(end -0.7874 -0.4064)
			(stroke
				(width 0.1524)
				(type default)
			)
			(layer "F.SilkS")
		)
		(fp_line
			(start 0.7874 -0.4064)
			(end 0.7874 0.4064)
			(stroke
				(width 0.1524)
				(type default)
			)
			(layer "F.SilkS")
		)
		(fp_line
			(start 0.7874 0.4064)
			(end -0.7874 0.4064)
			(stroke
				(width 0.1524)
				(type default)
			)
			(layer "F.SilkS")
		)
		(fp_line
			(start -0.67945 -0.305054)
			(end -0.12065 -0.305054)
			(stroke
				(width 0.1)
				(type default)
			)
			(layer "F.Fab")
		)
		(fp_line
			(start -0.67945 0.3048)
			(end -0.67945 -0.305054)
			(stroke
				(width 0.1)
				(type default)
			)
			(layer "F.Fab")
		)
		(fp_line
			(start -0.12065 -0.305054)
			(end -0.12065 -0.2794)
			(stroke
				(width 0.1)
				(type default)
			)
			(layer "F.Fab")
		)
		(fp_line
			(start -0.12065 -0.2794)
			(end 0.12065 -0.2794)
			(stroke
				(width 0.1)
				(type default)
			)
			(layer "F.Fab")
		)
		(fp_line
			(start -0.12065 0.2794)
			(end -0.12065 0.3048)
			(stroke
				(width 0.1)
				(type default)
			)
			(layer "F.Fab")
		)
		(fp_line
			(start -0.12065 0.3048)
			(end -0.67945 0.3048)
			(stroke
				(width 0.1)
				(type default)
			)
			(layer "F.Fab")
		)
		(fp_line
			(start 0.120396 0.2794)
			(end -0.12065 0.2794)
			(stroke
				(width 0.1)
				(type default)
			)
			(layer "F.Fab")
		)
		(fp_line
			(start 0.120396 0.3048)
			(end 0.120396 0.2794)
			(stroke
				(width 0.1)
				(type default)
			)
			(layer "F.Fab")
		)
		(fp_line
			(start 0.12065 -0.3048)
			(end 0.67945 -0.3048)
			(stroke
				(width 0.1)
				(type default)
			)
			(layer "F.Fab")
		)
		(fp_line
			(start 0.12065 -0.2794)
			(end 0.12065 -0.3048)
			(stroke
				(width 0.1)
				(type default)
			)
			(layer "F.Fab")
		)
		(fp_line
			(start 0.67945 -0.3048)
			(end 0.67945 0.3048)
			(stroke
				(width 0.1)
				(type default)
			)
			(layer "F.Fab")
		)
		(fp_line
			(start 0.67945 0.3048)
			(end 0.120396 0.3048)
			(stroke
				(width 0.1)
				(type default)
			)
			(layer "F.Fab")
		)
		(pad "1" smd circle
			(at -0.40005 0)
			(size 0 0)
			(layers "F.Cu" "F.Mask" "F.Paste")
			(net "P0V9_RETIMER_CPU0_LSET2")
		)
		(pad "2" smd circle
			(at 0.40005 0)
			(size 0 0)
			(layers "F.Cu" "F.Mask" "F.Paste")
			(net "GND")
		)
	)
)
